(kicad_pcb
	(version 20260206)
	(generator "pcbnew")
	(generator_version "10.0")
	(general
		(thickness 1.6)
		(legacy_teardrops no)
	)
	(paper "A4")
	(title_block
		(title "03242023_DA0F0TMBIJ0_F0T_Motherboard_J_brd_V01_OCP.brd")
		(comment 1 "Grand Teton / footprint 1187 of 6105 (U249), pads 315-422 of 484")
	)
	(layers
		(0 "F.Cu" signal "TOP")
		(4 "In1.Cu" signal "GND")
		(6 "In2.Cu" signal "IN1")
		(8 "In3.Cu" signal "GND1")
		(10 "In4.Cu" signal "IN2")
		(12 "In5.Cu" signal "GND2")
		(14 "In6.Cu" signal "IN3")
		(16 "In7.Cu" signal "GND3")
		(18 "In8.Cu" signal "VCC")
		(20 "In9.Cu" signal "VCC1")
		(22 "In10.Cu" signal "GND4")
		(24 "In11.Cu" signal "IN4")
		(26 "In12.Cu" signal "GND5")
		(28 "In13.Cu" signal "IN5")
		(30 "In14.Cu" signal "GND6")
		(32 "In15.Cu" signal "IN6")
		(34 "In16.Cu" signal "GND7")
		(2 "B.Cu" signal "BOTTOM")
		(9 "F.Adhes" user "F.Adhesive")
		(11 "B.Adhes" user "B.Adhesive")
		(13 "F.Paste" user "Package Geometry/Pastemask Top")
		(15 "B.Paste" user "Package Geometry/Pastemask Bottom")
		(5 "F.SilkS" user "Ref Des/Silkscreen Top")
		(7 "B.SilkS" user "Ref Des/Silkscreen Bottom")
		(1 "F.Mask" user "Board Geometry/Soldermask Top")
		(3 "B.Mask" user "Board Geometry/Soldermask Bottom")
		(17 "Dwgs.User" user "User.Drawings")
		(19 "Cmts.User" user "User.Comments")
		(21 "Eco1.User" user "User.Eco1")
		(23 "Eco2.User" user "User.Eco2")
		(25 "Edge.Cuts" user "Board Geometry/Outline")
		(27 "Margin" user)
		(31 "F.CrtYd" user "Package Geometry/Place Bound Top")
		(29 "B.CrtYd" user "Package Geometry/Place Bound Bottom")
		(35 "F.Fab" user "Ref Des/Assembly Top")
		(33 "B.Fab" user "Ref Des/Assembly Bottom")
	)
	(footprint ""
		(layer "F.Cu")
		(at 178.55565 -113.37544 90)
		(property "Reference" "U249"
			(at -11.966194 -11.833098 0)
			(unlocked yes)
			(layer "F.SilkS")
			(effects
				(font
					(size 0.7874 0.5842)
					(thickness 0.1524)
				)
				(justify left)
			)
		)
		(property "Value" ""
			(at 0 0 90)
			(layer "F.Fab")
			(effects
				(font
					(size 1.27 1.27)
				)
			)
		)
		(duplicate_pad_numbers_are_jumpers no)
		(pad "N7" smd circle
			(at -3.599942 1.199896 90)
			(size 0.4064 0.4064)
			(layers "F.Cu" "F.Mask" "F.Paste")
			(net "Net_1453")
		)
		(pad "N8" smd circle
			(at -2.800096 1.199896 90)
			(size 0.4064 0.4064)
			(layers "F.Cu" "F.Mask" "F.Paste")
			(net "P3V3_AUX_FPGA_VCCIO3")
		)
		(pad "N9" smd circle
			(at -1.999996 1.199896 90)
			(size 0.4064 0.4064)
			(layers "F.Cu" "F.Mask" "F.Paste")
			(net "GND")
		)
		(pad "N10" smd circle
			(at -1.199896 1.199896 90)
			(size 0.4064 0.4064)
			(layers "F.Cu" "F.Mask" "F.Paste")
			(net "VCC_PLD_CORE")
		)
		(pad "N11" smd circle
			(at -0.40005 1.199896 90)
			(size 0.4064 0.4064)
			(layers "F.Cu" "F.Mask" "F.Paste")
			(net "VCC_PLD_CORE")
		)
		(pad "N12" smd circle
			(at 0.40005 1.199896 90)
			(size 0.4064 0.4064)
			(layers "F.Cu" "F.Mask" "F.Paste")
			(net "VCC_PLD_CORE")
		)
		(pad "N13" smd circle
			(at 1.199896 1.199896 90)
			(size 0.4064 0.4064)
			(layers "F.Cu" "F.Mask" "F.Paste")
			(net "VCC_PLD_CORE")
		)
		(pad "N14" smd circle
			(at 1.999996 1.199896 90)
			(size 0.4064 0.4064)
			(layers "F.Cu" "F.Mask" "F.Paste")
			(net "GND")
		)
		(pad "N15" smd circle
			(at 2.800096 1.199896 90)
			(size 0.4064 0.4064)
			(layers "F.Cu" "F.Mask" "F.Paste")
			(net "P3V3_AUX_FPGA_VCCIO1")
		)
		(pad "N16" smd circle
			(at 3.599942 1.199896 90)
			(size 0.4064 0.4064)
			(layers "F.Cu" "F.Mask" "F.Paste")
			(net "FM_CPU1_SKTOCC_LVT3_PLD_N")
		)
		(pad "N17" smd circle
			(at 4.400042 1.199896 90)
			(size 0.4064 0.4064)
			(layers "F.Cu" "F.Mask" "F.Paste")
			(net "FM_CPU0_PROC_ID0")
		)
		(pad "N18" smd circle
			(at 5.199888 1.199896 90)
			(size 0.4064 0.4064)
			(layers "F.Cu" "F.Mask" "F.Paste")
			(net "FM_CPU0_PROC_ID1")
		)
		(pad "N19" smd circle
			(at 5.999988 1.199896 90)
			(size 0.4064 0.4064)
			(layers "F.Cu" "F.Mask" "F.Paste")
			(net "FM_CPU0_PKGID1")
		)
		(pad "N20" smd circle
			(at 6.800088 1.199896 90)
			(size 0.4064 0.4064)
			(layers "F.Cu" "F.Mask" "F.Paste")
			(net "FM_CPU0_PKGID0")
		)
		(pad "N21" smd circle
			(at 7.599934 1.199896 90)
			(size 0.4064 0.4064)
			(layers "F.Cu" "F.Mask" "F.Paste")
			(net "GND")
		)
		(pad "N22" smd circle
			(at 8.400034 1.199896 90)
			(size 0.4064 0.4064)
			(layers "F.Cu" "F.Mask" "F.Paste")
			(net "FM_CPU1_PROC_ID0")
		)
		(pad "P1" smd circle
			(at -8.400034 1.999996 90)
			(size 0.4064 0.4064)
			(layers "F.Cu" "F.Mask" "F.Paste")
			(net "Net_1444")
		)
		(pad "P2" smd circle
			(at -7.599934 1.999996 90)
			(size 0.4064 0.4064)
			(layers "F.Cu" "F.Mask" "F.Paste")
			(net "Net_1447")
		)
		(pad "P3" smd circle
			(at -6.800088 1.999996 90)
			(size 0.4064 0.4064)
			(layers "F.Cu" "F.Mask" "F.Paste")
			(net "Net_1449")
		)
		(pad "P4" smd circle
			(at -5.999988 1.999996 90)
			(size 0.4064 0.4064)
			(layers "F.Cu" "F.Mask" "F.Paste")
			(net "Net_750")
		)
		(pad "P5" smd circle
			(at -5.199888 1.999996 90)
			(size 0.4064 0.4064)
			(layers "F.Cu" "F.Mask" "F.Paste")
			(net "PWRGD_CPUPWRGD_LVC2_R1")
		)
		(pad "P6" smd circle
			(at -4.400042 1.999996 90)
			(size 0.4064 0.4064)
			(layers "F.Cu" "F.Mask" "F.Paste")
			(net "Net_442")
		)
		(pad "P7" smd circle
			(at -3.599942 1.999996 90)
			(size 0.4064 0.4064)
			(layers "F.Cu" "F.Mask" "F.Paste")
			(net "H_CPU1_THERMTRIP_LVC1_N")
		)
		(pad "P8" smd circle
			(at -2.800096 1.999996 90)
			(size 0.4064 0.4064)
			(layers "F.Cu" "F.Mask" "F.Paste")
			(net "P3V3_AUX_FPGA_VCCIO3")
		)
		(pad "P9" smd circle
			(at -1.999996 1.999996 90)
			(size 0.4064 0.4064)
			(layers "F.Cu" "F.Mask" "F.Paste")
			(net "GND")
		)
		(pad "P10" smd circle
			(at -1.199896 1.999996 90)
			(size 0.4064 0.4064)
			(layers "F.Cu" "F.Mask" "F.Paste")
			(net "GND")
		)
		(pad "P11" smd circle
			(at -0.40005 1.999996 90)
			(size 0.4064 0.4064)
			(layers "F.Cu" "F.Mask" "F.Paste")
			(net "GND")
		)
		(pad "P12" smd circle
			(at 0.40005 1.999996 90)
			(size 0.4064 0.4064)
			(layers "F.Cu" "F.Mask" "F.Paste")
			(net "GND")
		)
		(pad "P13" smd circle
			(at 1.199896 1.999996 90)
			(size 0.4064 0.4064)
			(layers "F.Cu" "F.Mask" "F.Paste")
			(net "GND")
		)
		(pad "P14" smd circle
			(at 1.999996 1.999996 90)
			(size 0.4064 0.4064)
			(layers "F.Cu" "F.Mask" "F.Paste")
			(net "GND")
		)
		(pad "P15" smd circle
			(at 2.800096 1.999996 90)
			(size 0.4064 0.4064)
			(layers "F.Cu" "F.Mask" "F.Paste")
			(net "P3V3_AUX_FPGA_VCCIO1")
		)
		(pad "P16" smd circle
			(at 3.599942 1.999996 90)
			(size 0.4064 0.4064)
			(layers "F.Cu" "F.Mask" "F.Paste")
			(net "FM_CPU_RMCA_CATERR_DLY_LVT3_R_N")
		)
		(pad "P17" smd circle
			(at 4.400042 1.999996 90)
			(size 0.4064 0.4064)
			(layers "F.Cu" "F.Mask" "F.Paste")
			(net "FM_RST_PERST_BIT1")
		)
		(pad "P18" smd circle
			(at 5.199888 1.999996 90)
			(size 0.4064 0.4064)
			(layers "F.Cu" "F.Mask" "F.Paste")
			(net "FM_RST_PERST_BIT0")
		)
		(pad "P19" smd circle
			(at 5.999988 1.999996 90)
			(size 0.4064 0.4064)
			(layers "F.Cu" "F.Mask" "F.Paste")
			(net "IRQ_PVCCIN_CPU1_VRHOT_R_N")
		)
		(pad "P20" smd circle
			(at 6.800088 1.999996 90)
			(size 0.4064 0.4064)
			(layers "F.Cu" "F.Mask" "F.Paste")
			(net "FM_CPU1_PKGID2")
		)
		(pad "P21" smd circle
			(at 7.599934 1.999996 90)
			(size 0.4064 0.4064)
			(layers "F.Cu" "F.Mask" "F.Paste")
			(net "FM_CPU1_PROC_ID1")
		)
		(pad "P22" smd circle
			(at 8.400034 1.999996 90)
			(size 0.4064 0.4064)
			(layers "F.Cu" "F.Mask" "F.Paste")
			(net "FM_CPU1_PKGID1")
		)
		(pad "R1" smd circle
			(at -8.400034 2.800096 90)
			(size 0.4064 0.4064)
			(layers "F.Cu" "F.Mask" "F.Paste")
			(net "Net_1448")
		)
		(pad "R2" smd circle
			(at -7.599934 2.800096 90)
			(size 0.4064 0.4064)
			(layers "F.Cu" "F.Mask" "F.Paste")
			(net "Net_1454")
		)
		(pad "R3" smd circle
			(at -6.800088 2.800096 90)
			(size 0.4064 0.4064)
			(layers "F.Cu" "F.Mask" "F.Paste")
			(net "Net_441")
		)
		(pad "R4" smd circle
			(at -5.999988 2.800096 90)
			(size 0.4064 0.4064)
			(layers "F.Cu" "F.Mask" "F.Paste")
			(net "Net_443")
		)
		(pad "R5" smd circle
			(at -5.199888 2.800096 90)
			(size 0.4064 0.4064)
			(layers "F.Cu" "F.Mask" "F.Paste")
			(net "Net_444")
		)
		(pad "R6" smd circle
			(at -4.400042 2.800096 90)
			(size 0.4064 0.4064)
			(layers "F.Cu" "F.Mask" "F.Paste")
			(net "H_CPU0_MEMTRIP_LVC1_N")
		)
		(pad "R7" smd circle
			(at -3.599942 2.800096 90)
			(size 0.4064 0.4064)
			(layers "F.Cu" "F.Mask" "F.Paste")
			(net "H_CPU1_MEMHOT_OUT_LVC1_N")
		)
		(pad "R8" smd circle
			(at -2.800096 2.800096 90)
			(size 0.4064 0.4064)
			(layers "F.Cu" "F.Mask" "F.Paste")
			(net "GND")
		)
		(pad "R9" smd circle
			(at -1.999996 2.800096 90)
			(size 0.4064 0.4064)
			(layers "F.Cu" "F.Mask" "F.Paste")
			(net "P3V3_AUX_FPGA_VCCIO2")
		)
		(pad "R10" smd circle
			(at -1.199896 2.800096 90)
			(size 0.4064 0.4064)
			(layers "F.Cu" "F.Mask" "F.Paste")
			(net "P3V3_AUX_FPGA_VCCIO2")
		)
		(pad "R11" smd circle
			(at -0.40005 2.800096 90)
			(size 0.4064 0.4064)
			(layers "F.Cu" "F.Mask" "F.Paste")
			(net "P3V3_AUX_FPGA_VCCIO2")
		)
		(pad "R12" smd circle
			(at 0.40005 2.800096 90)
			(size 0.4064 0.4064)
			(layers "F.Cu" "F.Mask" "F.Paste")
			(net "P3V3_AUX_FPGA_VCCIO2")
		)
		(pad "R13" smd circle
			(at 1.199896 2.800096 90)
			(size 0.4064 0.4064)
			(layers "F.Cu" "F.Mask" "F.Paste")
			(net "P3V3_AUX_FPGA_VCCIO2")
		)
		(pad "R14" smd circle
			(at 1.999996 2.800096 90)
			(size 0.4064 0.4064)
			(layers "F.Cu" "F.Mask" "F.Paste")
			(net "P3V3_AUX_FPGA_VCCIO2")
		)
		(pad "R15" smd circle
			(at 2.800096 2.800096 90)
			(size 0.4064 0.4064)
			(layers "F.Cu" "F.Mask" "F.Paste")
			(net "GND")
		)
		(pad "R16" smd circle
			(at 3.599942 2.800096 90)
			(size 0.4064 0.4064)
			(layers "F.Cu" "F.Mask" "F.Paste")
			(net "PWRGD_FAIL_CPU1_CD_R")
		)
		(pad "R17" smd circle
			(at 4.400042 2.800096 90)
			(size 0.4064 0.4064)
			(layers "F.Cu" "F.Mask" "F.Paste")
			(net "PWRGD_FAIL_CPU1_AB_R")
		)
		(pad "R18" smd circle
			(at 5.199888 2.800096 90)
			(size 0.4064 0.4064)
			(layers "F.Cu" "F.Mask" "F.Paste")
			(net "PWRGD_FAIL_CPU0_GH_R")
		)
		(pad "R19" smd circle
			(at 5.999988 2.800096 90)
			(size 0.4064 0.4064)
			(layers "F.Cu" "F.Mask" "F.Paste")
			(net "PWRGD_FAIL_CPU0_EF_R")
		)
		(pad "R20" smd circle
			(at 6.800088 2.800096 90)
			(size 0.4064 0.4064)
			(layers "F.Cu" "F.Mask" "F.Paste")
			(net "PWRGD_FAIL_CPU0_CD_R")
		)
		(pad "R21" smd circle
			(at 7.599934 2.800096 90)
			(size 0.4064 0.4064)
			(layers "F.Cu" "F.Mask" "F.Paste")
			(net "FM_CPU1_PKGID0")
		)
		(pad "R22" smd circle
			(at 8.400034 2.800096 90)
			(size 0.4064 0.4064)
			(layers "F.Cu" "F.Mask" "F.Paste")
			(net "FM_CPU0_PKGID2")
		)
		(pad "T1" smd circle
			(at -8.400034 3.599942 90)
			(size 0.4064 0.4064)
			(layers "F.Cu" "F.Mask" "F.Paste")
			(net "Net_1455")
		)
		(pad "T2" smd circle
			(at -7.599934 3.599942 90)
			(size 0.4064 0.4064)
			(layers "F.Cu" "F.Mask" "F.Paste")
			(net "H_CPU0_THERMTRIP_LVC1_N")
		)
		(pad "T3" smd circle
			(at -6.800088 3.599942 90)
			(size 0.4064 0.4064)
			(layers "F.Cu" "F.Mask" "F.Paste")
			(net "H_CPU0_MEMHOT_OUT_LVC1_N")
		)
		(pad "T4" smd circle
			(at -5.999988 3.599942 90)
			(size 0.4064 0.4064)
			(layers "F.Cu" "F.Mask" "F.Paste")
			(net "H_CPU_ERR2_LVC2_N")
		)
		(pad "T5" smd circle
			(at -5.199888 3.599942 90)
			(size 0.4064 0.4064)
			(layers "F.Cu" "F.Mask" "F.Paste")
			(net "H_CPU_ERR1_LVC2_N")
		)
		(pad "T6" smd circle
			(at -4.400042 3.599942 90)
			(size 0.4064 0.4064)
			(layers "F.Cu" "F.Mask" "F.Paste")
			(net "H_CPU_ERR0_LVC2_N")
		)
		(pad "T7" smd circle
			(at -3.599942 3.599942 90)
			(size 0.4064 0.4064)
			(layers "F.Cu" "F.Mask" "F.Paste")
			(net "H_CPU0_MEMHOT_IN_LVC1_R_N")
		)
		(pad "T8" smd circle
			(at -2.800096 3.599942 90)
			(size 0.4064 0.4064)
			(layers "F.Cu" "F.Mask" "F.Paste")
			(net "FM_PLD_CLK_25M_R_EN")
		)
		(pad "T9" smd circle
			(at -1.999996 3.599942 90)
			(size 0.4064 0.4064)
			(layers "F.Cu" "F.Mask" "F.Paste")
			(net "FM_BIOS_POST_CMPLT_BMC_N")
		)
		(pad "T10" smd circle
			(at -1.199896 3.599942 90)
			(size 0.4064 0.4064)
			(layers "F.Cu" "F.Mask" "F.Paste")
			(net "FM_PLD_HEARTBEAT_LVC3")
		)
		(pad "T11" smd circle
			(at -0.40005 3.599942 90)
			(size 0.4064 0.4064)
			(layers "F.Cu" "F.Mask" "F.Paste")
			(net "GPU_3V3IO_RSVD0_FFU_ISO_R")
		)
		(pad "T12" smd circle
			(at 0.40005 3.599942 90)
			(size 0.4064 0.4064)
			(layers "F.Cu" "F.Mask" "F.Paste")
			(net "GPU_3V3IO_RSVD1_ISO_R")
		)
		(pad "T13" smd circle
			(at 1.199896 3.599942 90)
			(size 0.4064 0.4064)
			(layers "F.Cu" "F.Mask" "F.Paste")
			(net "RST_SGPIO_RESET_N_R")
		)
		(pad "T14" smd circle
			(at 1.999996 3.599942 90)
			(size 0.4064 0.4064)
			(layers "F.Cu" "F.Mask" "F.Paste")
			(net "FM_ME_BT_DONE")
		)
		(pad "T15" smd circle
			(at 2.800096 3.599942 90)
			(size 0.4064 0.4064)
			(layers "F.Cu" "F.Mask" "F.Paste")
			(net "CLK_SWB_BUF2_OE_N")
		)
		(pad "T16" smd circle
			(at 3.599942 3.599942 90)
			(size 0.4064 0.4064)
			(layers "F.Cu" "F.Mask" "F.Paste")
			(net "FM_AC_PWR_BTN_PLD_ISO_N")
		)
		(pad "T17" smd circle
			(at 4.400042 3.599942 90)
			(size 0.4064 0.4064)
			(layers "F.Cu" "F.Mask" "F.Paste")
			(net "OCP_V3_2_MAIN_PWR_EN")
		)
		(pad "T18" smd circle
			(at 5.199888 3.599942 90)
			(size 0.4064 0.4064)
			(layers "F.Cu" "F.Mask" "F.Paste")
			(net "OCP_SFF_MAIN_PWR_EN")
		)
		(pad "T19" smd circle
			(at 5.999988 3.599942 90)
			(size 0.4064 0.4064)
			(layers "F.Cu" "F.Mask" "F.Paste")
			(net "PWRGD_FAIL_CPU1_GH_R")
		)
		(pad "T20" smd circle
			(at 6.800088 3.599942 90)
			(size 0.4064 0.4064)
			(layers "F.Cu" "F.Mask" "F.Paste")
			(net "PWRGD_FAIL_CPU1_EF_R")
		)
		(pad "T21" smd circle
			(at 7.599934 3.599942 90)
			(size 0.4064 0.4064)
			(layers "F.Cu" "F.Mask" "F.Paste")
			(net "IRQ_PVCCIN_CPU0_VRHOT_R_N")
		)
		(pad "T22" smd circle
			(at 8.400034 3.599942 90)
			(size 0.4064 0.4064)
			(layers "F.Cu" "F.Mask" "F.Paste")
			(net "PWRGD_DSW_PWROK_R3")
		)
		(pad "U1" smd circle
			(at -8.400034 4.400042 90)
			(size 0.4064 0.4064)
			(layers "F.Cu" "F.Mask" "F.Paste")
			(net "H_CPU1_MEMTRIP_LVC1_N")
		)
		(pad "U2" smd circle
			(at -7.599934 4.400042 90)
			(size 0.4064 0.4064)
			(layers "F.Cu" "F.Mask" "F.Paste")
			(net "Net_1456")
		)
		(pad "U3" smd circle
			(at -6.800088 4.400042 90)
			(size 0.4064 0.4064)
			(layers "F.Cu" "F.Mask" "F.Paste")
			(net "Net_1458")
		)
		(pad "U4" smd circle
			(at -5.999988 4.400042 90)
			(size 0.4064 0.4064)
			(layers "F.Cu" "F.Mask" "F.Paste")
			(net "Net_1459")
		)
		(pad "U5" smd circle
			(at -5.199888 4.400042 90)
			(size 0.4064 0.4064)
			(layers "F.Cu" "F.Mask" "F.Paste")
			(net "RST_CPU0_LVC1_R_N")
		)
		(pad "U6" smd circle
			(at -4.400042 4.400042 90)
			(size 0.4064 0.4064)
			(layers "F.Cu" "F.Mask" "F.Paste")
			(net "FM_ADR_COMPLETE")
		)
		(pad "U7" smd circle
			(at -3.599942 4.400042 90)
			(size 0.4064 0.4064)
			(layers "F.Cu" "F.Mask" "F.Paste")
			(net "FM_PLD_CLKS_DEV_R_EN")
		)
		(pad "U8" smd circle
			(at -2.800096 4.400042 90)
			(size 0.4064 0.4064)
			(layers "F.Cu" "F.Mask" "F.Paste")
			(net "FM_BMC_DBP_PRESENT_R_N")
		)
		(pad "U9" smd circle
			(at -1.999996 4.400042 90)
			(size 0.4064 0.4064)
			(layers "F.Cu" "F.Mask" "F.Paste")
			(net "FM_BMC_RSTBTN_OUT_N")
		)
		(pad "U10" smd circle
			(at -1.199896 4.400042 90)
			(size 0.4064 0.4064)
			(layers "F.Cu" "F.Mask" "F.Paste")
			(net "FM_FORCE_PWRON_LVC3")
		)
		(pad "U11" smd circle
			(at -0.40005 4.400042 90)
			(size 0.4064 0.4064)
			(layers "F.Cu" "F.Mask" "F.Paste")
			(net "GPU_3V3IO_RSVD1_FFU_ISO_R")
		)
		(pad "U12" smd circle
			(at 0.40005 4.400042 90)
			(size 0.4064 0.4064)
			(layers "F.Cu" "F.Mask" "F.Paste")
			(net "GPU_3V3IO_RSVD3_ISO_R")
		)
		(pad "U13" smd circle
			(at 1.199896 4.400042 90)
			(size 0.4064 0.4064)
			(layers "F.Cu" "F.Mask" "F.Paste")
			(net "IRQ_BMC_CPU_NMI_R1")
		)
		(pad "U14" smd circle
			(at 1.999996 4.400042 90)
			(size 0.4064 0.4064)
			(layers "F.Cu" "F.Mask" "F.Paste")
			(net "RST_PCIE_PCH_DEV_PERST_N")
		)
		(pad "U15" smd circle
			(at 2.800096 4.400042 90)
			(size 0.4064 0.4064)
			(layers "F.Cu" "F.Mask" "F.Paste")
			(net "FM_SLPS3_PLD_N")
		)
		(pad "U16" smd circle
			(at 3.599942 4.400042 90)
			(size 0.4064 0.4064)
			(layers "F.Cu" "F.Mask" "F.Paste")
			(net "NC_FPGA_PB43D")
		)
		(pad "U17" smd circle
			(at 4.400042 4.400042 90)
			(size 0.4064 0.4064)
			(layers "F.Cu" "F.Mask" "F.Paste")
			(net "FM_JTAG_TCK_MUX_SEL_R")
		)
		(pad "U18" smd circle
			(at 5.199888 4.400042 90)
			(size 0.4064 0.4064)
			(layers "F.Cu" "F.Mask" "F.Paste")
			(net "E1S_0_LED_ACT_R_N")
		)
		(pad "U19" smd circle
			(at 5.999988 4.400042 90)
			(size 0.4064 0.4064)
			(layers "F.Cu" "F.Mask" "F.Paste")
			(net "FM_SMB_2_ALERT_GPU_ISO_R_N")
		)
		(pad "U20" smd circle
			(at 6.800088 4.400042 90)
			(size 0.4064 0.4064)
			(layers "F.Cu" "F.Mask" "F.Paste")
			(net "HP_LVC3_OCP_V3_2_HSC_PWRGD_PLD_")
		)
		(pad "U21" smd circle
			(at 7.599934 4.400042 90)
			(size 0.4064 0.4064)
			(layers "F.Cu" "F.Mask" "F.Paste")
			(net "FM_SLPS4_PLD_N")
		)
		(pad "U22" smd circle
			(at 8.400034 4.400042 90)
			(size 0.4064 0.4064)
			(layers "F.Cu" "F.Mask" "F.Paste")
			(net "FM_JTAG_BMC_MUX_SEL_R")
		)
		(pad "V1" smd circle
			(at -8.400034 5.199888 90)
			(size 0.4064 0.4064)
			(layers "F.Cu" "F.Mask" "F.Paste")
			(net "Net_1457")
		)
		(pad "V2" smd circle
			(at -7.599934 5.199888 90)
			(size 0.4064 0.4064)
			(layers "F.Cu" "F.Mask" "F.Paste")
			(net "GND")
		)
		(pad "V3" smd circle
			(at -6.800088 5.199888 90)
			(size 0.4064 0.4064)
			(layers "F.Cu" "F.Mask" "F.Paste")
			(net "P3V3_AUX_FPGA_VCCIO3")
		)
		(pad "V4" smd circle
			(at -5.999988 5.199888 90)
			(size 0.4064 0.4064)
			(layers "F.Cu" "F.Mask" "F.Paste")
			(net "RST_CPU1_LVC1_R_N")
		)
	)
)
